# T6G (Grand Teton) — schematic netlist excerpt (pin names and nets, part order shuffled) for the footprints in the layout excerpt that follows; sources: Cadence DE-HDL packaged netlist, KiCad conversion of 04192023_DAF0TMB3IC0_F0TG_MB_C_brd_V02_OCP.brd

R226  Q_RES  0 5% CHIP  pkg 0402LF  page 82 : A = FM_PVDD11_S3_P0_OCP_N ; B = PVDD11_S3_P0_OCP_N
R6048  Q_RES  0 5% CHIP  pkg 0402LF  page 81 : A = HP_LVC3_E1S_0_HSC_PWRGD ; B = P12V_E1S_0_PWRGD
R1063  Q_RES  4.7K 5% EMPTY  pkg 0201LF  page 298 : A = P1V8_CPU0_RT_1D ; B = RT_CPU0_P2_SCAN_MODE

(kicad_pcb
	(version 20260206)
	(generator "pcbnew")
	(generator_version "10.0")
	(general
		(thickness 1.6)
		(legacy_teardrops no)
	)
	(paper "A4")
	(title_block
		(title "04192023_DAF0TMB3IC0_F0TG_MB_C_brd_V02_OCP.brd")
		(comment 1 "Grand Teton / footprints 8262-8264 of 8354")
	)
	(layers
		(0 "F.Cu" signal "TOP")
		(4 "In1.Cu" signal "GND")
		(6 "In2.Cu" signal "IN1")
		(8 "In3.Cu" signal "GND1")
		(10 "In4.Cu" signal "IN2")
		(12 "In5.Cu" signal "GND2")
		(14 "In6.Cu" signal "IN3")
		(16 "In7.Cu" signal "GND3")
		(18 "In8.Cu" signal "VCC")
		(20 "In9.Cu" signal "VCC1")
		(22 "In10.Cu" signal "GND4")
		(24 "In11.Cu" signal "IN4")
		(26 "In12.Cu" signal "GND5")
		(28 "In13.Cu" signal "IN5")
		(30 "In14.Cu" signal "GND6")
		(32 "In15.Cu" signal "IN6")
		(34 "In16.Cu" signal "GND7")
		(2 "B.Cu" signal "BOTTOM")
		(9 "F.Adhes" user "F.Adhesive")
		(11 "B.Adhes" user "B.Adhesive")
		(13 "F.Paste" user "Package Geometry/Pastemask Top")
		(15 "B.Paste" user "Package Geometry/Pastemask Bottom")
		(5 "F.SilkS" user "Ref Des/Silkscreen Top")
		(7 "B.SilkS" user "Ref Des/Silkscreen Bottom")
		(1 "F.Mask" user "Board Geometry/Soldermask Top")
		(3 "B.Mask" user "Board Geometry/Soldermask Bottom")
		(17 "Dwgs.User" user "User.Drawings")
		(19 "Cmts.User" user "User.Comments")
		(21 "Eco1.User" user "User.Eco1")
		(23 "Eco2.User" user "User.Eco2")
		(25 "Edge.Cuts" user "Board Geometry/Outline")
		(27 "Margin" user)
		(31 "F.CrtYd" user "Package Geometry/Place Bound Top")
		(29 "B.CrtYd" user "Package Geometry/Place Bound Bottom")
		(35 "F.Fab" user "Ref Des/Assembly Top")
		(33 "B.Fab" user "Ref Des/Assembly Bottom")
	)
	(footprint ""
		(layer "B.Cu")
		(at 181.737 -100.294948 90)
		(property "Reference" "R226"
			(at 0 0 90)
			(layer "B.SilkS")
			(hide yes)
			(effects
				(font
					(size 1.27 1.27)
				)
				(justify mirror)
			)
		)
		(property "Value" ""
			(at 0 0 90)
			(layer "B.Fab")
			(effects
				(font
					(size 1.27 1.27)
				)
				(justify mirror)
			)
		)
		(duplicate_pad_numbers_are_jumpers no)
		(fp_line
			(start 0.7874 -0.4064)
			(end -0.7874 -0.4064)
			(stroke
				(width 0.1524)
				(type default)
			)
			(layer "B.SilkS")
		)
		(fp_line
			(start -0.7874 -0.4064)
			(end -0.7874 0.4064)
			(stroke
				(width 0.1524)
				(type default)
			)
			(layer "B.SilkS")
		)
		(fp_line
			(start 0.7874 0.4064)
			(end 0.7874 -0.4064)
			(stroke
				(width 0.1524)
				(type default)
			)
			(layer "B.SilkS")
		)
		(fp_line
			(start -0.7874 0.4064)
			(end 0.7874 0.4064)
			(stroke
				(width 0.1524)
				(type default)
			)
			(layer "B.SilkS")
		)
		(fp_line
			(start 0.67945 -0.305054)
			(end 0.12065 -0.305054)
			(stroke
				(width 0.1)
				(type default)
			)
			(layer "B.Fab")
		)
		(fp_line
			(start 0.12065 -0.305054)
			(end 0.12065 -0.2794)
			(stroke
				(width 0.1)
				(type default)
			)
			(layer "B.Fab")
		)
		(fp_line
			(start -0.12065 -0.3048)
			(end -0.67945 -0.3048)
			(stroke
				(width 0.1)
				(type default)
			)
			(layer "B.Fab")
		)
		(fp_line
			(start -0.67945 -0.3048)
			(end -0.67945 0.3048)
			(stroke
				(width 0.1)
				(type default)
			)
			(layer "B.Fab")
		)
		(fp_line
			(start 0.12065 -0.2794)
			(end -0.12065 -0.2794)
			(stroke
				(width 0.1)
				(type default)
			)
			(layer "B.Fab")
		)
		(fp_line
			(start -0.12065 -0.2794)
			(end -0.12065 -0.3048)
			(stroke
				(width 0.1)
				(type default)
			)
			(layer "B.Fab")
		)
		(fp_line
			(start 0.12065 0.2794)
			(end 0.12065 0.3048)
			(stroke
				(width 0.1)
				(type default)
			)
			(layer "B.Fab")
		)
		(fp_line
			(start -0.120396 0.2794)
			(end 0.12065 0.2794)
			(stroke
				(width 0.1)
				(type default)
			)
			(layer "B.Fab")
		)
		(fp_line
			(start 0.67945 0.3048)
			(end 0.67945 -0.305054)
			(stroke
				(width 0.1)
				(type default)
			)
			(layer "B.Fab")
		)
		(fp_line
			(start 0.12065 0.3048)
			(end 0.67945 0.3048)
			(stroke
				(width 0.1)
				(type default)
			)
			(layer "B.Fab")
		)
		(fp_line
			(start -0.120396 0.3048)
			(end -0.120396 0.2794)
			(stroke
				(width 0.1)
				(type default)
			)
			(layer "B.Fab")
		)
		(fp_line
			(start -0.67945 0.3048)
			(end -0.120396 0.3048)
			(stroke
				(width 0.1)
				(type default)
			)
			(layer "B.Fab")
		)
		(pad "1" smd circle
			(at 0.40005 0 270)
			(size 0 0)
			(layers "B.Cu" "B.Mask" "B.Paste")
			(net "FM_PVDD11_S3_P0_OCP_N")
		)
		(pad "2" smd circle
			(at -0.40005 0 270)
			(size 0 0)
			(layers "B.Cu" "B.Mask" "B.Paste")
			(net "PVDD11_S3_P0_OCP_N")
		)
	)
	(footprint ""
		(layer "B.Cu")
		(at 397.623538 -392.1252 180)
		(property "Reference" "R1063"
			(at 0 0 0)
			(layer "B.SilkS")
			(hide yes)
			(effects
				(font
					(size 1.27 1.27)
				)
				(justify mirror)
			)
		)
		(property "Value" ""
			(at 0 0 0)
			(layer "B.Fab")
			(effects
				(font
					(size 1.27 1.27)
				)
				(justify mirror)
			)
		)
		(duplicate_pad_numbers_are_jumpers no)
		(fp_line
			(start 0.32512 0.175006)
			(end 0.32512 -0.175006)
			(stroke
				(width 0.1)
				(type default)
			)
			(layer "B.Fab")
		)
		(fp_line
			(start 0.32512 -0.175006)
			(end -0.32512 -0.175006)
			(stroke
				(width 0.1)
				(type default)
			)
			(layer "B.Fab")
		)
		(fp_line
			(start -0.32512 0.175006)
			(end 0.32512 0.175006)
			(stroke
				(width 0.1)
				(type default)
			)
			(layer "B.Fab")
		)
		(fp_line
			(start -0.32512 -0.175006)
			(end -0.32512 0.175006)
			(stroke
				(width 0.1)
				(type default)
			)
			(layer "B.Fab")
		)
		(pad "1" smd rect
			(at 0.2667 0)
			(size 0.3048 0.381)
			(layers "B.Cu" "B.Mask" "B.Paste")
			(net "P1V8_CPU0_RT_1D")
		)
		(pad "2" smd rect
			(at -0.2667 0 180)
			(size 0.3048 0.381)
			(layers "B.Cu" "B.Mask" "B.Paste")
			(net "RT_CPU0_P2_SCAN_MODE")
		)
	)
	(footprint ""
		(layer "B.Cu")
		(at 199.129396 -116.174012 -90)
		(property "Reference" "R6048"
			(at 0 0 90)
			(layer "B.SilkS")
			(hide yes)
			(effects
				(font
					(size 1.27 1.27)
				)
				(justify mirror)
			)
		)
		(property "Value" ""
			(at 0 0 90)
			(layer "B.Fab")
			(effects
				(font
					(size 1.27 1.27)
				)
				(justify mirror)
			)
		)
		(duplicate_pad_numbers_are_jumpers no)
		(fp_line
			(start -0.7874 0.4064)
			(end 0.7874 0.4064)
			(stroke
				(width 0.1524)
				(type default)
			)
			(layer "B.SilkS")
		)
		(fp_line
			(start 0.7874 0.4064)
			(end 0.7874 -0.4064)
			(stroke
				(width 0.1524)
				(type default)
			)
			(layer "B.SilkS")
		)
		(fp_line
			(start -0.7874 -0.4064)
			(end -0.7874 0.4064)
			(stroke
				(width 0.1524)
				(type default)
			)
			(layer "B.SilkS")
		)
		(fp_line
			(start 0.7874 -0.4064)
			(end -0.7874 -0.4064)
			(stroke
				(width 0.1524)
				(type default)
			)
			(layer "B.SilkS")
		)
		(fp_line
			(start -0.67945 0.3048)
			(end -0.120396 0.3048)
			(stroke
				(width 0.1)
				(type default)
			)
			(layer "B.Fab")
		)
		(fp_line
			(start -0.120396 0.3048)
			(end -0.120396 0.2794)
			(stroke
				(width 0.1)
				(type default)
			)
			(layer "B.Fab")
		)
		(fp_line
			(start 0.12065 0.3048)
			(end 0.67945 0.3048)
			(stroke
				(width 0.1)
				(type default)
			)
			(layer "B.Fab")
		)
		(fp_line
			(start 0.67945 0.3048)
			(end 0.67945 -0.305054)
			(stroke
				(width 0.1)
				(type default)
			)
			(layer "B.Fab")
		)
		(fp_line
			(start -0.120396 0.2794)
			(end 0.12065 0.2794)
			(stroke
				(width 0.1)
				(type default)
			)
			(layer "B.Fab")
		)
		(fp_line
			(start 0.12065 0.2794)
			(end 0.12065 0.3048)
			(stroke
				(width 0.1)
				(type default)
			)
			(layer "B.Fab")
		)
		(fp_line
			(start -0.12065 -0.2794)
			(end -0.12065 -0.3048)
			(stroke
				(width 0.1)
				(type default)
			)
			(layer "B.Fab")
		)
		(fp_line
			(start 0.12065 -0.2794)
			(end -0.12065 -0.2794)
			(stroke
				(width 0.1)
				(type default)
			)
			(layer "B.Fab")
		)
		(fp_line
			(start -0.67945 -0.3048)
			(end -0.67945 0.3048)
			(stroke
				(width 0.1)
				(type default)
			)
			(layer "B.Fab")
		)
		(fp_line
			(start -0.12065 -0.3048)
			(end -0.67945 -0.3048)
			(stroke
				(width 0.1)
				(type default)
			)
			(layer "B.Fab")
		)
		(fp_line
			(start 0.12065 -0.305054)
			(end 0.12065 -0.2794)
			(stroke
				(width 0.1)
				(type default)
			)
			(layer "B.Fab")
		)
		(fp_line
			(start 0.67945 -0.305054)
			(end 0.12065 -0.305054)
			(stroke
				(width 0.1)
				(type default)
			)
			(layer "B.Fab")
		)
		(pad "1" smd circle
			(at 0.40005 0 90)
			(size 0 0)
			(layers "B.Cu" "B.Mask" "B.Paste")
			(net "HP_LVC3_E1S_0_HSC_PWRGD")
		)
		(pad "2" smd circle
			(at -0.40005 0 90)
			(size 0 0)
			(layers "B.Cu" "B.Mask" "B.Paste")
			(net "P12V_E1S_0_PWRGD")
		)
	)
)
